(kicad_pcb
	(version 20260206)
	(generator "pcbnew")
	(generator_version "10.0")
	(general
		(thickness 1.6)
		(legacy_teardrops no)
	)
	(paper "A4")
	(title_block
		(title "01162023_DA0F0TEBIF0_F0T_Expander_BD_F_brd_V02_OCP.brd")
		(comment 1 "Grand Teton / footprints 1662-1669 of 9728")
	)
	(layers
		(0 "F.Cu" signal "TOP")
		(4 "In1.Cu" signal "GND")
		(6 "In2.Cu" signal "VCC")
		(8 "In3.Cu" signal "VCC1")
		(10 "In4.Cu" signal "GND1")
		(12 "In5.Cu" signal "IN1")
		(14 "In6.Cu" signal "GND2")
		(16 "In7.Cu" signal "IN2")
		(18 "In8.Cu" signal "GND3")
		(20 "In9.Cu" signal "IN3")
		(22 "In10.Cu" signal "GND4")
		(24 "In11.Cu" signal "IN4")
		(26 "In12.Cu" signal "GND5")
		(28 "In13.Cu" signal "IN5")
		(30 "In14.Cu" signal "GND6")
		(32 "In15.Cu" signal "IN6")
		(34 "In16.Cu" signal "GND7")
		(2 "B.Cu" signal "BOTTOM")
		(9 "F.Adhes" user "F.Adhesive")
		(11 "B.Adhes" user "B.Adhesive")
		(13 "F.Paste" user "Package Geometry/Pastemask Top")
		(15 "B.Paste" user "Package Geometry/Pastemask Bottom")
		(5 "F.SilkS" user "Ref Des/Silkscreen Top")
		(7 "B.SilkS" user "Ref Des/Silkscreen Bottom")
		(1 "F.Mask" user "Board Geometry/Soldermask Top")
		(3 "B.Mask" user "Board Geometry/Soldermask Bottom")
		(17 "Dwgs.User" user "User.Drawings")
		(19 "Cmts.User" user "User.Comments")
		(21 "Eco1.User" user "User.Eco1")
		(23 "Eco2.User" user "User.Eco2")
		(25 "Edge.Cuts" user "Board Geometry/Outline")
		(27 "Margin" user)
		(31 "F.CrtYd" user "Package Geometry/Place Bound Top")
		(29 "B.CrtYd" user "Package Geometry/Place Bound Bottom")
		(35 "F.Fab" user "Ref Des/Assembly Top")
		(33 "B.Fab" user "Ref Des/Assembly Bottom")
	)
	(footprint ""
		(layer "F.Cu")
		(at 146.253454 -300.992032)
		(property "Reference" "L105"
			(at 0 0 0)
			(layer "F.SilkS")
			(hide yes)
			(effects
				(font
					(size 1.27 1.27)
				)
			)
		)
		(property "Value" ""
			(at 0 0 0)
			(layer "F.Fab")
			(effects
				(font
					(size 1.27 1.27)
				)
			)
		)
		(duplicate_pad_numbers_are_jumpers no)
		(fp_line
			(start -1.63576 -0.8128)
			(end -1.63576 0.8128)
			(stroke
				(width 0.1524)
				(type default)
			)
			(layer "F.SilkS")
		)
		(fp_line
			(start -1.63576 -0.8128)
			(end 1.63576 -0.8128)
			(stroke
				(width 0.1524)
				(type default)
			)
			(layer "F.SilkS")
		)
		(fp_line
			(start 1.63576 -0.8128)
			(end 1.63576 0.8128)
			(stroke
				(width 0.1524)
				(type default)
			)
			(layer "F.SilkS")
		)
		(fp_line
			(start 1.63576 0.8128)
			(end -1.63576 0.8128)
			(stroke
				(width 0.1524)
				(type default)
			)
			(layer "F.SilkS")
		)
		(fp_line
			(start -1.56083 -0.738632)
			(end -1.56083 0.7366)
			(stroke
				(width 0.1)
				(type default)
			)
			(layer "F.Fab")
		)
		(fp_line
			(start -1.56083 0.7366)
			(end -1.524 0.7366)
			(stroke
				(width 0.1)
				(type default)
			)
			(layer "F.Fab")
		)
		(fp_line
			(start -1.524 0.7366)
			(end 1.524 0.7366)
			(stroke
				(width 0.1)
				(type default)
			)
			(layer "F.Fab")
		)
		(fp_line
			(start 1.524 0.7366)
			(end 1.560576 0.7366)
			(stroke
				(width 0.1)
				(type default)
			)
			(layer "F.Fab")
		)
		(fp_line
			(start 1.560576 -0.738632)
			(end -1.56083 -0.738632)
			(stroke
				(width 0.1)
				(type default)
			)
			(layer "F.Fab")
		)
		(fp_line
			(start 1.560576 0.7366)
			(end 1.560576 -0.738632)
			(stroke
				(width 0.1)
				(type default)
			)
			(layer "F.Fab")
		)
		(pad "1" smd rect
			(at -0.94996 0 180)
			(size 1.1176 1.3716)
			(layers "F.Cu" "F.Mask" "F.Paste")
			(net "P1V8_PLL0_PEX1")
		)
		(pad "2" smd rect
			(at 0.94996 0 180)
			(size 1.1176 1.3716)
			(layers "F.Cu" "F.Mask" "F.Paste")
			(net "PCEPLL1_VDDA18_PEX1")
		)
	)
	(footprint ""
		(layer "F.Cu")
		(at 56.271922 -363.356144 -90)
		(property "Reference" "R5451"
			(at 0 0 270)
			(layer "F.SilkS")
			(hide yes)
			(effects
				(font
					(size 1.27 1.27)
				)
			)
		)
		(property "Value" ""
			(at 0 0 270)
			(layer "F.Fab")
			(effects
				(font
					(size 1.27 1.27)
				)
			)
		)
		(duplicate_pad_numbers_are_jumpers no)
		(fp_line
			(start 0.028448 0.4064)
			(end -0.7874 0.4064)
			(stroke
				(width 0.1524)
				(type default)
			)
			(layer "F.SilkS")
		)
		(fp_line
			(start -0.7874 -0.4064)
			(end 0.7874 -0.4064)
			(stroke
				(width 0.1524)
				(type default)
			)
			(layer "F.SilkS")
		)
		(fp_line
			(start 0.7874 -0.4064)
			(end 0.7874 0.4064)
			(stroke
				(width 0.1524)
				(type default)
			)
			(layer "F.SilkS")
		)
		(fp_line
			(start -0.67945 0.3048)
			(end -0.67945 -0.305054)
			(stroke
				(width 0.1)
				(type default)
			)
			(layer "F.Fab")
		)
		(fp_line
			(start -0.12065 0.3048)
			(end -0.67945 0.3048)
			(stroke
				(width 0.1)
				(type default)
			)
			(layer "F.Fab")
		)
		(fp_line
			(start 0.120396 0.3048)
			(end 0.120396 0.2794)
			(stroke
				(width 0.1)
				(type default)
			)
			(layer "F.Fab")
		)
		(fp_line
			(start 0.67945 0.3048)
			(end 0.120396 0.3048)
			(stroke
				(width 0.1)
				(type default)
			)
			(layer "F.Fab")
		)
		(fp_line
			(start -0.12065 0.2794)
			(end -0.12065 0.3048)
			(stroke
				(width 0.1)
				(type default)
			)
			(layer "F.Fab")
		)
		(fp_line
			(start 0.120396 0.2794)
			(end -0.12065 0.2794)
			(stroke
				(width 0.1)
				(type default)
			)
			(layer "F.Fab")
		)
		(fp_line
			(start -0.12065 -0.2794)
			(end 0.12065 -0.2794)
			(stroke
				(width 0.1)
				(type default)
			)
			(layer "F.Fab")
		)
		(fp_line
			(start 0.12065 -0.2794)
			(end 0.12065 -0.3048)
			(stroke
				(width 0.1)
				(type default)
			)
			(layer "F.Fab")
		)
		(fp_line
			(start 0.12065 -0.3048)
			(end 0.67945 -0.3048)
			(stroke
				(width 0.1)
				(type default)
			)
			(layer "F.Fab")
		)
		(fp_line
			(start 0.67945 -0.3048)
			(end 0.67945 0.3048)
			(stroke
				(width 0.1)
				(type default)
			)
			(layer "F.Fab")
		)
		(fp_line
			(start -0.67945 -0.305054)
			(end -0.12065 -0.305054)
			(stroke
				(width 0.1)
				(type default)
			)
			(layer "F.Fab")
		)
		(fp_line
			(start -0.12065 -0.305054)
			(end -0.12065 -0.2794)
			(stroke
				(width 0.1)
				(type default)
			)
			(layer "F.Fab")
		)
		(pad "1" smd rect
			(at -0.40005 0 90)
			(size 0.4572 0.508)
			(layers "F.Cu" "F.Mask" "F.Paste")
			(net "USB2_GPU_HMC_R_DP")
		)
		(pad "2" smd rect
			(at 0.40005 0 90)
			(size 0.4572 0.508)
			(layers "F.Cu" "F.Mask" "F.Paste")
			(net "USB2_GPU_HMC_DP")
		)
	)
	(footprint ""
		(layer "F.Cu")
		(at 321.804284 -343.952322 90)
		(property "Reference" "C541"
			(at 0 0 90)
			(layer "F.SilkS")
			(hide yes)
			(effects
				(font
					(size 1.27 1.27)
				)
			)
		)
		(property "Value" ""
			(at 0 0 90)
			(layer "F.Fab")
			(effects
				(font
					(size 1.27 1.27)
				)
			)
		)
		(duplicate_pad_numbers_are_jumpers no)
		(fp_line
			(start 0.299974 -0.150114)
			(end 0.299974 0.150114)
			(stroke
				(width 0.1)
				(type default)
			)
			(layer "F.Fab")
		)
		(fp_line
			(start -0.299974 -0.150114)
			(end 0.299974 -0.150114)
			(stroke
				(width 0.1)
				(type default)
			)
			(layer "F.Fab")
		)
		(fp_line
			(start 0.299974 0.150114)
			(end -0.299974 0.150114)
			(stroke
				(width 0.1)
				(type default)
			)
			(layer "F.Fab")
		)
		(fp_line
			(start -0.299974 0.150114)
			(end -0.299974 -0.150114)
			(stroke
				(width 0.1)
				(type default)
			)
			(layer "F.Fab")
		)
		(pad "1" smd rect
			(at -0.2667 0 90)
			(size 0.3048 0.381)
			(layers "F.Cu" "F.Mask" "F.Paste")
			(net "P5E_PEX2_STN5_TX_DP<84>")
		)
		(pad "2" smd rect
			(at 0.2667 0 90)
			(size 0.3048 0.381)
			(layers "F.Cu" "F.Mask" "F.Paste")
			(net "P5E_PEX2_STN5_TX_C_DP<84>")
		)
	)
	(footprint ""
		(layer "F.Cu")
		(at 454.754742 -22.961346 90)
		(property "Reference" "R1732"
			(at 0 0 90)
			(layer "F.SilkS")
			(hide yes)
			(effects
				(font
					(size 1.27 1.27)
				)
			)
		)
		(property "Value" ""
			(at 0 0 90)
			(layer "F.Fab")
			(effects
				(font
					(size 1.27 1.27)
				)
			)
		)
		(duplicate_pad_numbers_are_jumpers no)
		(fp_line
			(start 0.7874 -0.4064)
			(end 0.7874 0.4064)
			(stroke
				(width 0.1524)
				(type default)
			)
			(layer "F.SilkS")
		)
		(fp_line
			(start -0.7874 -0.4064)
			(end 0.7874 -0.4064)
			(stroke
				(width 0.1524)
				(type default)
			)
			(layer "F.SilkS")
		)
		(fp_line
			(start 0.7874 0.4064)
			(end -0.7874 0.4064)
			(stroke
				(width 0.1524)
				(type default)
			)
			(layer "F.SilkS")
		)
		(fp_line
			(start -0.7874 0.4064)
			(end -0.7874 -0.4064)
			(stroke
				(width 0.1524)
				(type default)
			)
			(layer "F.SilkS")
		)
		(fp_line
			(start -0.12065 -0.305054)
			(end -0.12065 -0.2794)
			(stroke
				(width 0.1)
				(type default)
			)
			(layer "F.Fab")
		)
		(fp_line
			(start -0.67945 -0.305054)
			(end -0.12065 -0.305054)
			(stroke
				(width 0.1)
				(type default)
			)
			(layer "F.Fab")
		)
		(fp_line
			(start 0.67945 -0.3048)
			(end 0.67945 0.3048)
			(stroke
				(width 0.1)
				(type default)
			)
			(layer "F.Fab")
		)
		(fp_line
			(start 0.12065 -0.3048)
			(end 0.67945 -0.3048)
			(stroke
				(width 0.1)
				(type default)
			)
			(layer "F.Fab")
		)
		(fp_line
			(start 0.12065 -0.2794)
			(end 0.12065 -0.3048)
			(stroke
				(width 0.1)
				(type default)
			)
			(layer "F.Fab")
		)
		(fp_line
			(start -0.12065 -0.2794)
			(end 0.12065 -0.2794)
			(stroke
				(width 0.1)
				(type default)
			)
			(layer "F.Fab")
		)
		(fp_line
			(start 0.120396 0.2794)
			(end -0.12065 0.2794)
			(stroke
				(width 0.1)
				(type default)
			)
			(layer "F.Fab")
		)
		(fp_line
			(start -0.12065 0.2794)
			(end -0.12065 0.3048)
			(stroke
				(width 0.1)
				(type default)
			)
			(layer "F.Fab")
		)
		(fp_line
			(start 0.67945 0.3048)
			(end 0.120396 0.3048)
			(stroke
				(width 0.1)
				(type default)
			)
			(layer "F.Fab")
		)
		(fp_line
			(start 0.120396 0.3048)
			(end 0.120396 0.2794)
			(stroke
				(width 0.1)
				(type default)
			)
			(layer "F.Fab")
		)
		(fp_line
			(start -0.12065 0.3048)
			(end -0.67945 0.3048)
			(stroke
				(width 0.1)
				(type default)
			)
			(layer "F.Fab")
		)
		(fp_line
			(start -0.67945 0.3048)
			(end -0.67945 -0.305054)
			(stroke
				(width 0.1)
				(type default)
			)
			(layer "F.Fab")
		)
		(pad "1" smd circle
			(at -0.40005 0 90)
			(size 0 0)
			(layers "F.Cu" "F.Mask" "F.Paste")
			(net "SMB_SSD15_ISO_EN")
		)
		(pad "2" smd circle
			(at 0.40005 0 90)
			(size 0 0)
			(layers "F.Cu" "F.Mask" "F.Paste")
			(net "P3V3_AUX")
		)
	)
	(footprint ""
		(layer "F.Cu")
		(at 277.198582 -356.244906 90)
		(property "Reference" "C603"
			(at 0 0 90)
			(layer "F.SilkS")
			(hide yes)
			(effects
				(font
					(size 1.27 1.27)
				)
			)
		)
		(property "Value" ""
			(at 0 0 90)
			(layer "F.Fab")
			(effects
				(font
					(size 1.27 1.27)
				)
			)
		)
		(duplicate_pad_numbers_are_jumpers no)
		(fp_line
			(start 0.299974 -0.150114)
			(end 0.299974 0.150114)
			(stroke
				(width 0.1)
				(type default)
			)
			(layer "F.Fab")
		)
		(fp_line
			(start -0.299974 -0.150114)
			(end 0.299974 -0.150114)
			(stroke
				(width 0.1)
				(type default)
			)
			(layer "F.Fab")
		)
		(fp_line
			(start 0.299974 0.150114)
			(end -0.299974 0.150114)
			(stroke
				(width 0.1)
				(type default)
			)
			(layer "F.Fab")
		)
		(fp_line
			(start -0.299974 0.150114)
			(end -0.299974 -0.150114)
			(stroke
				(width 0.1)
				(type default)
			)
			(layer "F.Fab")
		)
		(pad "1" smd rect
			(at -0.2667 0 90)
			(size 0.3048 0.381)
			(layers "F.Cu" "F.Mask" "F.Paste")
			(net "P5E_PEX2_STN7_TX_DP<117>")
		)
		(pad "2" smd rect
			(at 0.2667 0 90)
			(size 0.3048 0.381)
			(layers "F.Cu" "F.Mask" "F.Paste")
			(net "P5E_PEX2_STN7_TX_C_DP<117>")
		)
	)
	(footprint ""
		(layer "F.Cu")
		(at 336.924396 -119.77624)
		(property "Reference" "Q217"
			(at -0.051816 -2.817622 0)
			(unlocked yes)
			(layer "F.SilkS")
			(effects
				(font
					(size 0.7874 0.5842)
					(thickness 0.1524)
				)
			)
		)
		(property "Value" ""
			(at 0 0 0)
			(layer "F.Fab")
			(effects
				(font
					(size 1.27 1.27)
				)
			)
		)
		(duplicate_pad_numbers_are_jumpers no)
		(fp_line
			(start -1.376172 -1.199896)
			(end -0.508 -1.199896)
			(stroke
				(width 0.1524)
				(type default)
			)
			(layer "F.SilkS")
		)
		(fp_line
			(start -1.376172 1.199896)
			(end -1.376172 -1.199896)
			(stroke
				(width 0.1524)
				(type default)
			)
			(layer "F.SilkS")
		)
		(fp_line
			(start -0.508 -1.199896)
			(end 0 -0.762)
			(stroke
				(width 0.1524)
				(type default)
			)
			(layer "F.SilkS")
		)
		(fp_line
			(start 0 -0.762)
			(end 0.508 -1.199896)
			(stroke
				(width 0.1524)
				(type default)
			)
			(layer "F.SilkS")
		)
		(fp_line
			(start 0.508 -1.199896)
			(end 1.376172 -1.199896)
			(stroke
				(width 0.1524)
				(type default)
			)
			(layer "F.SilkS")
		)
		(fp_line
			(start 1.376172 -1.199896)
			(end 1.376172 1.199896)
			(stroke
				(width 0.1524)
				(type default)
			)
			(layer "F.SilkS")
		)
		(fp_line
			(start 1.376172 1.199896)
			(end -1.376172 1.199896)
			(stroke
				(width 0.1524)
				(type default)
			)
			(layer "F.SilkS")
		)
		(fp_poly
			(pts
				(xy -0.9652 -1.325118) (xy -1.234694 -2.133346) (xy -1.773428 -1.594612)
			)
			(stroke
				(width 0)
				(type default)
			)
			(fill yes)
			(layer "F.SilkS")
		)
		(fp_line
			(start -0.674878 -1.100074)
			(end 0.674878 -1.100074)
			(stroke
				(width 0.1)
				(type default)
			)
			(layer "F.Fab")
		)
		(fp_line
			(start -0.674878 1.100074)
			(end -0.674878 -1.100074)
			(stroke
				(width 0.1)
				(type default)
			)
			(layer "F.Fab")
		)
		(fp_line
			(start 0.674878 -1.100074)
			(end 0.674878 1.100074)
			(stroke
				(width 0.1)
				(type default)
			)
			(layer "F.Fab")
		)
		(fp_line
			(start 0.674878 1.100074)
			(end -0.674878 1.100074)
			(stroke
				(width 0.1)
				(type default)
			)
			(layer "F.Fab")
		)
		(fp_poly
			(pts
				(xy -1.4605 -0.7493) (xy -2.2225 -1.1303) (xy -2.2225 -0.3683)
			)
			(stroke
				(width 0)
				(type default)
			)
			(fill yes)
			(layer "F.Fab")
		)
		(pad "1" smd rect
			(at -0.899922 -0.750062 270)
			(size 0.6096 0.6096)
			(layers "F.Cu" "F.Mask" "F.Paste")
			(net "GND")
		)
		(pad "2" smd rect
			(at -0.899922 0 270)
			(size 0.4064 0.6096)
			(layers "F.Cu" "F.Mask" "F.Paste")
			(net "P3V3_NIC5_PG_G1")
		)
		(pad "3" smd rect
			(at -0.899922 0.750062 270)
			(size 0.6096 0.6096)
			(layers "F.Cu" "F.Mask" "F.Paste")
			(net "PWRGD_P3V3_NIC5_D")
		)
		(pad "4" smd rect
			(at 0.899922 0.750062 270)
			(size 0.6096 0.6096)
			(layers "F.Cu" "F.Mask" "F.Paste")
			(net "GND")
		)
		(pad "5" smd rect
			(at 0.899922 0 270)
			(size 0.4064 0.6096)
			(layers "F.Cu" "F.Mask" "F.Paste")
			(net "P3V3_NIC5_PG_G2")
		)
		(pad "6" smd rect
			(at 0.899922 -0.750062 270)
			(size 0.6096 0.6096)
			(layers "F.Cu" "F.Mask" "F.Paste")
			(net "P3V3_NIC5_PG_G2")
		)
	)
	(footprint ""
		(layer "F.Cu")
		(at 379.307344 -260.639814 -90)
		(property "Reference" "C3556"
			(at 0 0 270)
			(layer "F.SilkS")
			(hide yes)
			(effects
				(font
					(size 1.27 1.27)
				)
			)
		)
		(property "Value" ""
			(at 0 0 270)
			(layer "F.Fab")
			(effects
				(font
					(size 1.27 1.27)
				)
			)
		)
		(duplicate_pad_numbers_are_jumpers no)
		(fp_line
			(start -0.299974 0.150114)
			(end -0.299974 -0.150114)
			(stroke
				(width 0.1)
				(type default)
			)
			(layer "F.Fab")
		)
		(fp_line
			(start 0.299974 0.150114)
			(end -0.299974 0.150114)
			(stroke
				(width 0.1)
				(type default)
			)
			(layer "F.Fab")
		)
		(fp_line
			(start -0.299974 -0.150114)
			(end 0.299974 -0.150114)
			(stroke
				(width 0.1)
				(type default)
			)
			(layer "F.Fab")
		)
		(fp_line
			(start 0.299974 -0.150114)
			(end 0.299974 0.150114)
			(stroke
				(width 0.1)
				(type default)
			)
			(layer "F.Fab")
		)
		(pad "1" smd rect
			(at -0.2667 0 270)
			(size 0.3048 0.381)
			(layers "F.Cu" "F.Mask" "F.Paste")
			(net "P1V8_PLL0_PEX3")
		)
		(pad "2" smd rect
			(at 0.2667 0 270)
			(size 0.3048 0.381)
			(layers "F.Cu" "F.Mask" "F.Paste")
			(net "GND")
		)
	)
	(footprint ""
		(layer "F.Cu")
		(at 122.752612 -156.288994 -90)
		(property "Reference" "PR6886"
			(at 0 0 270)
			(layer "F.SilkS")
			(hide yes)
			(effects
				(font
					(size 1.27 1.27)
				)
			)
		)
		(property "Value" ""
			(at 0 0 270)
			(layer "F.Fab")
			(effects
				(font
					(size 1.27 1.27)
				)
			)
		)
		(duplicate_pad_numbers_are_jumpers no)
		(fp_line
			(start -0.7874 0.4064)
			(end -0.7874 -0.4064)
			(stroke
				(width 0.1524)
				(type default)
			)
			(layer "F.SilkS")
		)
		(fp_line
			(start 0.7874 0.4064)
			(end -0.7874 0.4064)
			(stroke
				(width 0.1524)
				(type default)
			)
			(layer "F.SilkS")
		)
		(fp_line
			(start -0.7874 -0.4064)
			(end 0.7874 -0.4064)
			(stroke
				(width 0.1524)
				(type default)
			)
			(layer "F.SilkS")
		)
		(fp_line
			(start 0.7874 -0.4064)
			(end 0.7874 0.4064)
			(stroke
				(width 0.1524)
				(type default)
			)
			(layer "F.SilkS")
		)
		(fp_line
			(start -0.67945 0.3048)
			(end -0.67945 -0.305054)
			(stroke
				(width 0.1)
				(type default)
			)
			(layer "F.Fab")
		)
		(fp_line
			(start -0.12065 0.3048)
			(end -0.67945 0.3048)
			(stroke
				(width 0.1)
				(type default)
			)
			(layer "F.Fab")
		)
		(fp_line
			(start 0.120396 0.3048)
			(end 0.120396 0.2794)
			(stroke
				(width 0.1)
				(type default)
			)
			(layer "F.Fab")
		)
		(fp_line
			(start 0.67945 0.3048)
			(end 0.120396 0.3048)
			(stroke
				(width 0.1)
				(type default)
			)
			(layer "F.Fab")
		)
		(fp_line
			(start -0.12065 0.2794)
			(end -0.12065 0.3048)
			(stroke
				(width 0.1)
				(type default)
			)
			(layer "F.Fab")
		)
		(fp_line
			(start 0.120396 0.2794)
			(end -0.12065 0.2794)
			(stroke
				(width 0.1)
				(type default)
			)
			(layer "F.Fab")
		)
		(fp_line
			(start -0.12065 -0.2794)
			(end 0.12065 -0.2794)
			(stroke
				(width 0.1)
				(type default)
			)
			(layer "F.Fab")
		)
		(fp_line
			(start 0.12065 -0.2794)
			(end 0.12065 -0.3048)
			(stroke
				(width 0.1)
				(type default)
			)
			(layer "F.Fab")
		)
		(fp_line
			(start 0.12065 -0.3048)
			(end 0.67945 -0.3048)
			(stroke
				(width 0.1)
				(type default)
			)
			(layer "F.Fab")
		)
		(fp_line
			(start 0.67945 -0.3048)
			(end 0.67945 0.3048)
			(stroke
				(width 0.1)
				(type default)
			)
			(layer "F.Fab")
		)
		(fp_line
			(start -0.67945 -0.305054)
			(end -0.12065 -0.305054)
			(stroke
				(width 0.1)
				(type default)
			)
			(layer "F.Fab")
		)
		(fp_line
			(start -0.12065 -0.305054)
			(end -0.12065 -0.2794)
			(stroke
				(width 0.1)
				(type default)
			)
			(layer "F.Fab")
		)
		(pad "1" smd circle
			(at -0.40005 0 270)
			(size 0 0)
			(layers "F.Cu" "F.Mask" "F.Paste")
			(net "P12V_NIC2_CO_OV_FB")
		)
		(pad "2" smd circle
			(at 0.40005 0 270)
			(size 0 0)
			(layers "F.Cu" "F.Mask" "F.Paste")
			(net "P12V_NIC2_R")
		)
	)
)
